# T6G (Grand Teton) — schematic netlist excerpt (pin names and nets, part order shuffled) for the footprints in the layout excerpt that follows; sources: Cadence DE-HDL packaged netlist, KiCad conversion of 04192023_DAF0TMB3IC0_F0TG_MB_C_brd_V02_OCP.brd

PC102_1  Q_CAP  22UF 4V 20% X6S  pkg C0805  page 201 : A = PVDDCR_CPU1_P0 ; B = GND
L6004  Q_INDUCTOR  BLM21PG221SN1D IND  pkg SMLF  page 179 : \1\ = P1V2_AUX ; \2\ = P1V2_CPU0_USB2_DVDD12
R326  Q_RES  0 5% CHIP  pkg 0402LF  page 161 : A = SMB_CPU0_CPU1_APML_SDA_R2 ; B = SMB_CPU0_CPU1_APML_MUX2_SDA

(kicad_pcb
	(version 20260206)
	(generator "pcbnew")
	(generator_version "10.0")
	(general
		(thickness 1.6)
		(legacy_teardrops no)
	)
	(paper "A4")
	(title_block
		(title "04192023_DAF0TMB3IC0_F0TG_MB_C_brd_V02_OCP.brd")
		(comment 1 "Grand Teton / footprints 6473-6475 of 8354")
	)
	(layers
		(0 "F.Cu" signal "TOP")
		(4 "In1.Cu" signal "GND")
		(6 "In2.Cu" signal "IN1")
		(8 "In3.Cu" signal "GND1")
		(10 "In4.Cu" signal "IN2")
		(12 "In5.Cu" signal "GND2")
		(14 "In6.Cu" signal "IN3")
		(16 "In7.Cu" signal "GND3")
		(18 "In8.Cu" signal "VCC")
		(20 "In9.Cu" signal "VCC1")
		(22 "In10.Cu" signal "GND4")
		(24 "In11.Cu" signal "IN4")
		(26 "In12.Cu" signal "GND5")
		(28 "In13.Cu" signal "IN5")
		(30 "In14.Cu" signal "GND6")
		(32 "In15.Cu" signal "IN6")
		(34 "In16.Cu" signal "GND7")
		(2 "B.Cu" signal "BOTTOM")
		(9 "F.Adhes" user "F.Adhesive")
		(11 "B.Adhes" user "B.Adhesive")
		(13 "F.Paste" user "Package Geometry/Pastemask Top")
		(15 "B.Paste" user "Package Geometry/Pastemask Bottom")
		(5 "F.SilkS" user "Ref Des/Silkscreen Top")
		(7 "B.SilkS" user "Ref Des/Silkscreen Bottom")
		(1 "F.Mask" user "Board Geometry/Soldermask Top")
		(3 "B.Mask" user "Board Geometry/Soldermask Bottom")
		(17 "Dwgs.User" user "User.Drawings")
		(19 "Cmts.User" user "User.Comments")
		(21 "Eco1.User" user "User.Eco1")
		(23 "Eco2.User" user "User.Eco2")
		(25 "Edge.Cuts" user "Board Geometry/Outline")
		(27 "Margin" user)
		(31 "F.CrtYd" user "Package Geometry/Place Bound Top")
		(29 "B.CrtYd" user "Package Geometry/Place Bound Bottom")
		(35 "F.Fab" user "Ref Des/Assembly Top")
		(33 "B.Fab" user "Ref Des/Assembly Bottom")
	)
	(footprint ""
		(layer "B.Cu")
		(at 338.186522 -326.341232 -90)
		(property "Reference" "PC102_1"
			(at 0 0 90)
			(layer "B.SilkS")
			(hide yes)
			(effects
				(font
					(size 1.27 1.27)
				)
				(justify mirror)
			)
		)
		(property "Value" ""
			(at 0 0 90)
			(layer "B.Fab")
			(effects
				(font
					(size 1.27 1.27)
				)
				(justify mirror)
			)
		)
		(duplicate_pad_numbers_are_jumpers no)
		(fp_line
			(start -1.524 0.762)
			(end 1.524 0.762)
			(stroke
				(width 0.1524)
				(type default)
			)
			(layer "B.SilkS")
		)
		(fp_line
			(start 1.524 0.762)
			(end 1.524 -0.762)
			(stroke
				(width 0.1524)
				(type default)
			)
			(layer "B.SilkS")
		)
		(fp_line
			(start -1.524 -0.762)
			(end -1.524 0.762)
			(stroke
				(width 0.1524)
				(type default)
			)
			(layer "B.SilkS")
		)
		(fp_line
			(start 1.524 -0.762)
			(end -1.524 -0.762)
			(stroke
				(width 0.1524)
				(type default)
			)
			(layer "B.SilkS")
		)
		(fp_line
			(start -1.1049 0.724916)
			(end -1.1049 -0.724916)
			(stroke
				(width 0.1)
				(type default)
			)
			(layer "B.Fab")
		)
		(fp_line
			(start 1.1049 0.724916)
			(end -1.1049 0.724916)
			(stroke
				(width 0.1)
				(type default)
			)
			(layer "B.Fab")
		)
		(fp_line
			(start -1.1049 -0.724916)
			(end 1.1049 -0.724916)
			(stroke
				(width 0.1)
				(type default)
			)
			(layer "B.Fab")
		)
		(fp_line
			(start 1.1049 -0.724916)
			(end 1.1049 0.724916)
			(stroke
				(width 0.1)
				(type default)
			)
			(layer "B.Fab")
		)
		(pad "1" smd rect
			(at 0.889 0 270)
			(size 1.016 1.27)
			(layers "B.Cu" "B.Mask" "B.Paste")
			(net "PVDDCR_CPU1_P0")
		)
		(pad "2" smd rect
			(at -0.889 0 270)
			(size 1.016 1.27)
			(layers "B.Cu" "B.Mask" "B.Paste")
			(net "GND")
		)
	)
	(footprint ""
		(layer "B.Cu")
		(at 230.505 -243.2431 -90)
		(property "Reference" "R326"
			(at 0 0 90)
			(layer "B.SilkS")
			(hide yes)
			(effects
				(font
					(size 1.27 1.27)
				)
				(justify mirror)
			)
		)
		(property "Value" ""
			(at 0 0 90)
			(layer "B.Fab")
			(effects
				(font
					(size 1.27 1.27)
				)
				(justify mirror)
			)
		)
		(duplicate_pad_numbers_are_jumpers no)
		(fp_line
			(start -0.7874 0.4064)
			(end 0.7874 0.4064)
			(stroke
				(width 0.1524)
				(type default)
			)
			(layer "B.SilkS")
		)
		(fp_line
			(start 0.7874 0.4064)
			(end 0.7874 -0.4064)
			(stroke
				(width 0.1524)
				(type default)
			)
			(layer "B.SilkS")
		)
		(fp_line
			(start -0.7874 -0.4064)
			(end -0.7874 0.4064)
			(stroke
				(width 0.1524)
				(type default)
			)
			(layer "B.SilkS")
		)
		(fp_line
			(start 0.7874 -0.4064)
			(end -0.7874 -0.4064)
			(stroke
				(width 0.1524)
				(type default)
			)
			(layer "B.SilkS")
		)
		(fp_line
			(start -0.67945 0.3048)
			(end -0.120396 0.3048)
			(stroke
				(width 0.1)
				(type default)
			)
			(layer "B.Fab")
		)
		(fp_line
			(start -0.120396 0.3048)
			(end -0.120396 0.2794)
			(stroke
				(width 0.1)
				(type default)
			)
			(layer "B.Fab")
		)
		(fp_line
			(start 0.12065 0.3048)
			(end 0.67945 0.3048)
			(stroke
				(width 0.1)
				(type default)
			)
			(layer "B.Fab")
		)
		(fp_line
			(start 0.67945 0.3048)
			(end 0.67945 -0.305054)
			(stroke
				(width 0.1)
				(type default)
			)
			(layer "B.Fab")
		)
		(fp_line
			(start -0.120396 0.2794)
			(end 0.12065 0.2794)
			(stroke
				(width 0.1)
				(type default)
			)
			(layer "B.Fab")
		)
		(fp_line
			(start 0.12065 0.2794)
			(end 0.12065 0.3048)
			(stroke
				(width 0.1)
				(type default)
			)
			(layer "B.Fab")
		)
		(fp_line
			(start -0.12065 -0.2794)
			(end -0.12065 -0.3048)
			(stroke
				(width 0.1)
				(type default)
			)
			(layer "B.Fab")
		)
		(fp_line
			(start 0.12065 -0.2794)
			(end -0.12065 -0.2794)
			(stroke
				(width 0.1)
				(type default)
			)
			(layer "B.Fab")
		)
		(fp_line
			(start -0.67945 -0.3048)
			(end -0.67945 0.3048)
			(stroke
				(width 0.1)
				(type default)
			)
			(layer "B.Fab")
		)
		(fp_line
			(start -0.12065 -0.3048)
			(end -0.67945 -0.3048)
			(stroke
				(width 0.1)
				(type default)
			)
			(layer "B.Fab")
		)
		(fp_line
			(start 0.12065 -0.305054)
			(end 0.12065 -0.2794)
			(stroke
				(width 0.1)
				(type default)
			)
			(layer "B.Fab")
		)
		(fp_line
			(start 0.67945 -0.305054)
			(end 0.12065 -0.305054)
			(stroke
				(width 0.1)
				(type default)
			)
			(layer "B.Fab")
		)
		(pad "1" smd rect
			(at 0.40005 0 270)
			(size 0.4572 0.508)
			(layers "B.Cu" "B.Mask" "B.Paste")
			(net "SMB_CPU0_CPU1_APML_SDA_R2")
		)
		(pad "2" smd rect
			(at -0.40005 0 270)
			(size 0.4572 0.508)
			(layers "B.Cu" "B.Mask" "B.Paste")
			(net "SMB_CPU0_CPU1_APML_MUX2_SDA")
		)
	)
	(footprint ""
		(layer "B.Cu")
		(at 115.705636 -36.138866 90)
		(property "Reference" "L6004"
			(at 0 0 90)
			(layer "B.SilkS")
			(hide yes)
			(effects
				(font
					(size 1.27 1.27)
				)
				(justify mirror)
			)
		)
		(property "Value" ""
			(at 0 0 90)
			(layer "B.Fab")
			(effects
				(font
					(size 1.27 1.27)
				)
				(justify mirror)
			)
		)
		(duplicate_pad_numbers_are_jumpers no)
		(fp_line
			(start 1.63576 -0.8128)
			(end -1.63576 -0.8128)
			(stroke
				(width 0.1524)
				(type default)
			)
			(layer "B.SilkS")
		)
		(fp_line
			(start 1.63576 -0.8128)
			(end 1.63576 0.8128)
			(stroke
				(width 0.1524)
				(type default)
			)
			(layer "B.SilkS")
		)
		(fp_line
			(start -1.63576 -0.8128)
			(end -1.63576 0.8128)
			(stroke
				(width 0.1524)
				(type default)
			)
			(layer "B.SilkS")
		)
		(fp_line
			(start -1.63576 0.8128)
			(end 1.63576 0.8128)
			(stroke
				(width 0.1524)
				(type default)
			)
			(layer "B.SilkS")
		)
		(fp_line
			(start 1.56083 -0.738632)
			(end 1.56083 0.7366)
			(stroke
				(width 0.1)
				(type default)
			)
			(layer "B.Fab")
		)
		(fp_line
			(start -1.560576 -0.738632)
			(end 1.56083 -0.738632)
			(stroke
				(width 0.1)
				(type default)
			)
			(layer "B.Fab")
		)
		(fp_line
			(start 1.56083 0.7366)
			(end 1.524 0.7366)
			(stroke
				(width 0.1)
				(type default)
			)
			(layer "B.Fab")
		)
		(fp_line
			(start 1.524 0.7366)
			(end -1.524 0.7366)
			(stroke
				(width 0.1)
				(type default)
			)
			(layer "B.Fab")
		)
		(fp_line
			(start -1.524 0.7366)
			(end -1.560576 0.7366)
			(stroke
				(width 0.1)
				(type default)
			)
			(layer "B.Fab")
		)
		(fp_line
			(start -1.560576 0.7366)
			(end -1.560576 -0.738632)
			(stroke
				(width 0.1)
				(type default)
			)
			(layer "B.Fab")
		)
		(pad "1" smd rect
			(at 0.94996 0 90)
			(size 1.1176 1.3716)
			(layers "B.Cu" "B.Mask" "B.Paste")
			(net "P1V2_AUX")
		)
		(pad "2" smd rect
			(at -0.94996 0 90)
			(size 1.1176 1.3716)
			(layers "B.Cu" "B.Mask" "B.Paste")
			(net "P1V2_CPU0_USB2_DVDD12")
		)
	)
)
